(kicad_pcb
	(version 20260206)
	(generator "pcbnew")
	(generator_version "10.0")
	(general
		(thickness 1.6)
		(legacy_teardrops no)
	)
	(paper "A4")
	(title_block
		(title "01162023_DA0F0TEBIF0_F0T_Expander_BD_F_brd_V02_OCP.brd")
		(comment 1 "Grand Teton / footprints 2703-2708 of 9728")
	)
	(layers
		(0 "F.Cu" signal "TOP")
		(4 "In1.Cu" signal "GND")
		(6 "In2.Cu" signal "VCC")
		(8 "In3.Cu" signal "VCC1")
		(10 "In4.Cu" signal "GND1")
		(12 "In5.Cu" signal "IN1")
		(14 "In6.Cu" signal "GND2")
		(16 "In7.Cu" signal "IN2")
		(18 "In8.Cu" signal "GND3")
		(20 "In9.Cu" signal "IN3")
		(22 "In10.Cu" signal "GND4")
		(24 "In11.Cu" signal "IN4")
		(26 "In12.Cu" signal "GND5")
		(28 "In13.Cu" signal "IN5")
		(30 "In14.Cu" signal "GND6")
		(32 "In15.Cu" signal "IN6")
		(34 "In16.Cu" signal "GND7")
		(2 "B.Cu" signal "BOTTOM")
		(9 "F.Adhes" user "F.Adhesive")
		(11 "B.Adhes" user "B.Adhesive")
		(13 "F.Paste" user "Package Geometry/Pastemask Top")
		(15 "B.Paste" user "Package Geometry/Pastemask Bottom")
		(5 "F.SilkS" user "Ref Des/Silkscreen Top")
		(7 "B.SilkS" user "Ref Des/Silkscreen Bottom")
		(1 "F.Mask" user "Board Geometry/Soldermask Top")
		(3 "B.Mask" user "Board Geometry/Soldermask Bottom")
		(17 "Dwgs.User" user "User.Drawings")
		(19 "Cmts.User" user "User.Comments")
		(21 "Eco1.User" user "User.Eco1")
		(23 "Eco2.User" user "User.Eco2")
		(25 "Edge.Cuts" user "Board Geometry/Outline")
		(27 "Margin" user)
		(31 "F.CrtYd" user "Package Geometry/Place Bound Top")
		(29 "B.CrtYd" user "Package Geometry/Place Bound Bottom")
		(35 "F.Fab" user "Ref Des/Assembly Top")
		(33 "B.Fab" user "Ref Des/Assembly Bottom")
	)
	(footprint ""
		(layer "F.Cu")
		(at 358.013 -214.376)
		(property "Reference" "R4091"
			(at 0 0 0)
			(layer "F.SilkS")
			(hide yes)
			(effects
				(font
					(size 1.27 1.27)
				)
			)
		)
		(property "Value" ""
			(at 0 0 0)
			(layer "F.Fab")
			(effects
				(font
					(size 1.27 1.27)
				)
			)
		)
		(duplicate_pad_numbers_are_jumpers no)
		(fp_line
			(start -0.7874 -0.4064)
			(end 0.7874 -0.4064)
			(stroke
				(width 0.1524)
				(type default)
			)
			(layer "F.SilkS")
		)
		(fp_line
			(start -0.7874 0.4064)
			(end -0.7874 -0.4064)
			(stroke
				(width 0.1524)
				(type default)
			)
			(layer "F.SilkS")
		)
		(fp_line
			(start 0.7874 -0.4064)
			(end 0.7874 0.4064)
			(stroke
				(width 0.1524)
				(type default)
			)
			(layer "F.SilkS")
		)
		(fp_line
			(start 0.7874 0.4064)
			(end -0.7874 0.4064)
			(stroke
				(width 0.1524)
				(type default)
			)
			(layer "F.SilkS")
		)
		(fp_line
			(start -0.67945 -0.305054)
			(end -0.12065 -0.305054)
			(stroke
				(width 0.1)
				(type default)
			)
			(layer "F.Fab")
		)
		(fp_line
			(start -0.67945 0.3048)
			(end -0.67945 -0.305054)
			(stroke
				(width 0.1)
				(type default)
			)
			(layer "F.Fab")
		)
		(fp_line
			(start -0.12065 -0.305054)
			(end -0.12065 -0.2794)
			(stroke
				(width 0.1)
				(type default)
			)
			(layer "F.Fab")
		)
		(fp_line
			(start -0.12065 -0.2794)
			(end 0.12065 -0.2794)
			(stroke
				(width 0.1)
				(type default)
			)
			(layer "F.Fab")
		)
		(fp_line
			(start -0.12065 0.2794)
			(end -0.12065 0.3048)
			(stroke
				(width 0.1)
				(type default)
			)
			(layer "F.Fab")
		)
		(fp_line
			(start -0.12065 0.3048)
			(end -0.67945 0.3048)
			(stroke
				(width 0.1)
				(type default)
			)
			(layer "F.Fab")
		)
		(fp_line
			(start 0.120396 0.2794)
			(end -0.12065 0.2794)
			(stroke
				(width 0.1)
				(type default)
			)
			(layer "F.Fab")
		)
		(fp_line
			(start 0.120396 0.3048)
			(end 0.120396 0.2794)
			(stroke
				(width 0.1)
				(type default)
			)
			(layer "F.Fab")
		)
		(fp_line
			(start 0.12065 -0.3048)
			(end 0.67945 -0.3048)
			(stroke
				(width 0.1)
				(type default)
			)
			(layer "F.Fab")
		)
		(fp_line
			(start 0.12065 -0.2794)
			(end 0.12065 -0.3048)
			(stroke
				(width 0.1)
				(type default)
			)
			(layer "F.Fab")
		)
		(fp_line
			(start 0.67945 -0.3048)
			(end 0.67945 0.3048)
			(stroke
				(width 0.1)
				(type default)
			)
			(layer "F.Fab")
		)
		(fp_line
			(start 0.67945 0.3048)
			(end 0.120396 0.3048)
			(stroke
				(width 0.1)
				(type default)
			)
			(layer "F.Fab")
		)
		(pad "1" smd circle
			(at -0.40005 0)
			(size 0 0)
			(layers "F.Cu" "F.Mask" "F.Paste")
			(net "NIC7_CLK_EN_N")
		)
		(pad "2" smd circle
			(at 0.40005 0)
			(size 0 0)
			(layers "F.Cu" "F.Mask" "F.Paste")
			(net "NIC7_CLK_EN_R_N")
		)
	)
	(footprint ""
		(layer "F.Cu")
		(at 366.955578 -90.642694 180)
		(property "Reference" "R1599"
			(at 0 0 180)
			(layer "F.SilkS")
			(hide yes)
			(effects
				(font
					(size 1.27 1.27)
				)
			)
		)
		(property "Value" ""
			(at 0 0 180)
			(layer "F.Fab")
			(effects
				(font
					(size 1.27 1.27)
				)
			)
		)
		(duplicate_pad_numbers_are_jumpers no)
		(fp_line
			(start 0.7874 0.4064)
			(end -0.7874 0.4064)
			(stroke
				(width 0.1524)
				(type default)
			)
			(layer "F.SilkS")
		)
		(fp_line
			(start 0.7874 -0.4064)
			(end 0.7874 0.4064)
			(stroke
				(width 0.1524)
				(type default)
			)
			(layer "F.SilkS")
		)
		(fp_line
			(start -0.7874 0.4064)
			(end -0.7874 -0.4064)
			(stroke
				(width 0.1524)
				(type default)
			)
			(layer "F.SilkS")
		)
		(fp_line
			(start -0.7874 -0.4064)
			(end 0.7874 -0.4064)
			(stroke
				(width 0.1524)
				(type default)
			)
			(layer "F.SilkS")
		)
		(fp_line
			(start 0.67945 0.3048)
			(end 0.120396 0.3048)
			(stroke
				(width 0.1)
				(type default)
			)
			(layer "F.Fab")
		)
		(fp_line
			(start 0.67945 -0.3048)
			(end 0.67945 0.3048)
			(stroke
				(width 0.1)
				(type default)
			)
			(layer "F.Fab")
		)
		(fp_line
			(start 0.12065 -0.2794)
			(end 0.12065 -0.3048)
			(stroke
				(width 0.1)
				(type default)
			)
			(layer "F.Fab")
		)
		(fp_line
			(start 0.12065 -0.3048)
			(end 0.67945 -0.3048)
			(stroke
				(width 0.1)
				(type default)
			)
			(layer "F.Fab")
		)
		(fp_line
			(start 0.120396 0.3048)
			(end 0.120396 0.2794)
			(stroke
				(width 0.1)
				(type default)
			)
			(layer "F.Fab")
		)
		(fp_line
			(start 0.120396 0.2794)
			(end -0.12065 0.2794)
			(stroke
				(width 0.1)
				(type default)
			)
			(layer "F.Fab")
		)
		(fp_line
			(start -0.12065 0.3048)
			(end -0.67945 0.3048)
			(stroke
				(width 0.1)
				(type default)
			)
			(layer "F.Fab")
		)
		(fp_line
			(start -0.12065 0.2794)
			(end -0.12065 0.3048)
			(stroke
				(width 0.1)
				(type default)
			)
			(layer "F.Fab")
		)
		(fp_line
			(start -0.12065 -0.2794)
			(end 0.12065 -0.2794)
			(stroke
				(width 0.1)
				(type default)
			)
			(layer "F.Fab")
		)
		(fp_line
			(start -0.12065 -0.305054)
			(end -0.12065 -0.2794)
			(stroke
				(width 0.1)
				(type default)
			)
			(layer "F.Fab")
		)
		(fp_line
			(start -0.67945 0.3048)
			(end -0.67945 -0.305054)
			(stroke
				(width 0.1)
				(type default)
			)
			(layer "F.Fab")
		)
		(fp_line
			(start -0.67945 -0.305054)
			(end -0.12065 -0.305054)
			(stroke
				(width 0.1)
				(type default)
			)
			(layer "F.Fab")
		)
		(pad "1" smd circle
			(at -0.40005 0 180)
			(size 0 0)
			(layers "F.Cu" "F.Mask" "F.Paste")
			(net "P3V3_AUX")
		)
		(pad "2" smd circle
			(at 0.40005 0 180)
			(size 0 0)
			(layers "F.Cu" "F.Mask" "F.Paste")
			(net "BIC_I2C9_SSD_MUX1_A2")
		)
	)
	(footprint ""
		(layer "F.Cu")
		(at 337.693 -241.808 -90)
		(property "Reference" "U144"
			(at -2.547366 -2.030984 90)
			(unlocked yes)
			(layer "F.SilkS")
			(effects
				(font
					(size 0.7874 0.5842)
					(thickness 0.1524)
				)
			)
		)
		(property "Value" ""
			(at 0 0 270)
			(layer "F.Fab")
			(effects
				(font
					(size 1.27 1.27)
				)
			)
		)
		(duplicate_pad_numbers_are_jumpers no)
		(fp_line
			(start -1.7272 1.1176)
			(end -1.7272 -1.1176)
			(stroke
				(width 0.1524)
				(type default)
			)
			(layer "F.SilkS")
		)
		(fp_line
			(start 1.7272 1.1176)
			(end -1.7272 1.1176)
			(stroke
				(width 0.1524)
				(type default)
			)
			(layer "F.SilkS")
		)
		(fp_line
			(start 0 -0.7366)
			(end -0.254 -1.1176)
			(stroke
				(width 0.1524)
				(type default)
			)
			(layer "F.SilkS")
		)
		(fp_line
			(start -0.254 -1.1176)
			(end -1.7272 -1.1176)
			(stroke
				(width 0.1524)
				(type default)
			)
			(layer "F.SilkS")
		)
		(fp_line
			(start 0.254 -1.1176)
			(end 0 -0.7366)
			(stroke
				(width 0.1524)
				(type default)
			)
			(layer "F.SilkS")
		)
		(fp_line
			(start 1.7272 -1.1176)
			(end 1.7272 1.1176)
			(stroke
				(width 0.1524)
				(type default)
			)
			(layer "F.SilkS")
		)
		(fp_line
			(start 1.7272 -1.1176)
			(end 0.254 -1.1176)
			(stroke
				(width 0.1524)
				(type default)
			)
			(layer "F.SilkS")
		)
		(fp_poly
			(pts
				(xy -1.9558 -0.649986) (xy -2.7178 -0.268986) (xy -2.7178 -1.030986)
			)
			(stroke
				(width 0)
				(type default)
			)
			(fill yes)
			(layer "F.SilkS")
		)
		(fp_line
			(start -1.5748 1.1176)
			(end 1.5748 1.1176)
			(stroke
				(width 0.1)
				(type default)
			)
			(layer "F.Fab")
		)
		(fp_line
			(start 1.5748 1.1176)
			(end 1.5748 -1.1176)
			(stroke
				(width 0.1)
				(type default)
			)
			(layer "F.Fab")
		)
		(fp_line
			(start -1.5748 -1.1176)
			(end -1.5748 1.1176)
			(stroke
				(width 0.1)
				(type default)
			)
			(layer "F.Fab")
		)
		(fp_line
			(start 1.5748 -1.1176)
			(end -1.5748 -1.1176)
			(stroke
				(width 0.1)
				(type default)
			)
			(layer "F.Fab")
		)
		(fp_poly
			(pts
				(xy -1.9558 -0.649986) (xy -2.7178 -0.268986) (xy -2.7178 -1.030986)
			)
			(stroke
				(width 0)
				(type default)
			)
			(fill yes)
			(layer "F.Fab")
		)
		(pad "1" smd rect
			(at -0.999998 -0.649986 180)
			(size 0.3556 1.1176)
			(layers "F.Cu" "F.Mask" "F.Paste")
			(net "RST_MB_PERST_2_N")
		)
		(pad "2" smd rect
			(at -0.999998 0 180)
			(size 0.3556 1.1176)
			(layers "F.Cu" "F.Mask" "F.Paste")
			(net "GND")
		)
		(pad "3" smd rect
			(at -0.999998 0.649986 180)
			(size 0.3556 1.1176)
			(layers "F.Cu" "F.Mask" "F.Paste")
			(net "MB_SWB_PWR_EN")
		)
		(pad "4" smd rect
			(at 0.999998 0.649986 180)
			(size 0.3556 1.1176)
			(layers "F.Cu" "F.Mask" "F.Paste")
			(net "MB_SWB_PWR_EN_ISO")
		)
		(pad "5" smd rect
			(at 0.999998 0 180)
			(size 0.3556 1.1176)
			(layers "F.Cu" "F.Mask" "F.Paste")
			(net "P3V3_AUX")
		)
		(pad "6" smd rect
			(at 0.999998 -0.649986 180)
			(size 0.3556 1.1176)
			(layers "F.Cu" "F.Mask" "F.Paste")
			(net "RST_MB_PERST_2_ISO_N")
		)
	)
	(footprint ""
		(layer "F.Cu")
		(at 224.074482 -441.524644)
		(property "Reference" "X67"
			(at -0.1778 -1.92913 0)
			(unlocked yes)
			(layer "F.SilkS")
			(effects
				(font
					(size 0.7874 0.5842)
					(thickness 0.1524)
				)
				(justify left)
			)
		)
		(property "Value" ""
			(at 0 0 0)
			(layer "F.Fab")
			(effects
				(font
					(size 1.27 1.27)
				)
			)
		)
		(property "Device Type" "TP_TDR_4P_FTS_MPKT4_H025P0200_IO_TP15_TP_TDR_4P_DIP"
			(at 1.30175 1.27 90)
			(unlocked yes)
			(layer "F.Fab")
			(hide yes)
			(effects
				(font
					(size 0.635 0.4064)
					(thickness 0.1524)
				)
			)
		)
		(property "User Part Number" "TP15"
			(at 1.30175 1.27 90)
			(unlocked yes)
			(layer "Cmts.User")
			(hide yes)
			(effects
				(font
					(size 0.635 0.4064)
					(thickness 0.1524)
				)
			)
		)
		(duplicate_pad_numbers_are_jumpers no)
		(fp_line
			(start 0 -1.27)
			(end 0 -0.635)
			(stroke
				(width 0.1524)
				(type default)
			)
			(layer "F.SilkS")
		)
		(fp_line
			(start 0 0.635)
			(end 0 1.905)
			(stroke
				(width 0.1524)
				(type default)
			)
			(layer "F.SilkS")
		)
		(fp_line
			(start 0 3.175)
			(end 0 3.81)
			(stroke
				(width 0.1524)
				(type default)
			)
			(layer "F.SilkS")
		)
		(fp_line
			(start 0 3.81)
			(end 2.54 3.81)
			(stroke
				(width 0.1524)
				(type default)
			)
			(layer "F.SilkS")
		)
		(fp_line
			(start 2.54 -1.27)
			(end 0 -1.27)
			(stroke
				(width 0.1524)
				(type default)
			)
			(layer "F.SilkS")
		)
		(fp_line
			(start 2.54 -1.1303)
			(end 2.54 -1.27)
			(stroke
				(width 0.1524)
				(type default)
			)
			(layer "F.SilkS")
		)
		(fp_line
			(start 2.54 1.4097)
			(end 2.54 1.1303)
			(stroke
				(width 0.1524)
				(type default)
			)
			(layer "F.SilkS")
		)
		(fp_line
			(start 2.54 3.81)
			(end 2.54 3.6703)
			(stroke
				(width 0.1524)
				(type default)
			)
			(layer "F.SilkS")
		)
		(fp_poly
			(pts
				(xy -0.761746 0) (xy -2.285746 -0.762) (xy -2.285746 0.762)
			)
			(stroke
				(width 0)
				(type default)
			)
			(fill yes)
			(layer "F.SilkS")
		)
		(fp_line
			(start 0 -1.27)
			(end 0 3.81)
			(stroke
				(width 0.1)
				(type default)
			)
			(layer "F.Fab")
		)
		(fp_line
			(start 0 3.81)
			(end 2.54 3.81)
			(stroke
				(width 0.1)
				(type default)
			)
			(layer "F.Fab")
		)
		(fp_line
			(start 2.54 -1.27)
			(end 0 -1.27)
			(stroke
				(width 0.1)
				(type default)
			)
			(layer "F.Fab")
		)
		(fp_line
			(start 2.54 3.81)
			(end 2.54 -1.27)
			(stroke
				(width 0.1)
				(type default)
			)
			(layer "F.Fab")
		)
		(fp_poly
			(pts
				(xy -0.761746 0) (xy -2.285746 -0.762) (xy -2.285746 0.762)
			)
			(stroke
				(width 0)
				(type default)
			)
			(fill yes)
			(layer "F.Fab")
		)
		(pad "1" thru_hole circle
			(at 0 0)
			(size 1.0033 1.0033)
			(drill 0.249936)
			(layers "*.Cu" "*.Mask")
			(remove_unused_layers no)
			(net "TDR_DIFF_100_TOP_DIN")
			(clearance 0.10795)
			(thermal_gap 0.10795)
			(padstack
				(mode front_inner_back)
				(layer "Inner"
					(shape circle)
					(size 0.8001 0.8001)
					(clearance 0.1524)
				)
				(layer "B.Cu"
					(shape circle)
					(size 1.0033 1.0033)
					(clearance 0.10795)
				)
			)
		)
		(pad "2" thru_hole circle
			(at 2.54 0)
			(size 1.9939 1.9939)
			(drill 0.249936)
			(layers "*.Cu" "*.Mask")
			(remove_unused_layers no)
			(net "COUPON_GND1")
			(clearance 0.10795)
			(thermal_gap 0.10795)
			(padstack
				(mode front_inner_back)
				(layer "Inner"
					(shape circle)
					(size 0.8001 0.8001)
					(clearance 0.1524)
				)
				(layer "B.Cu"
					(shape circle)
					(size 1.9939 1.9939)
					(clearance 0.10795)
				)
			)
		)
		(pad "3" thru_hole circle
			(at 2.54 2.54)
			(size 1.9939 1.9939)
			(drill 0.249936)
			(layers "*.Cu" "*.Mask")
			(remove_unused_layers no)
			(net "COUPON_GND1")
			(clearance 0.10795)
			(thermal_gap 0.10795)
			(padstack
				(mode front_inner_back)
				(layer "Inner"
					(shape circle)
					(size 0.8001 0.8001)
					(clearance 0.1524)
				)
				(layer "B.Cu"
					(shape circle)
					(size 1.9939 1.9939)
					(clearance 0.10795)
				)
			)
		)
		(pad "4" thru_hole circle
			(at 0 2.54)
			(size 1.0033 1.0033)
			(drill 0.249936)
			(layers "*.Cu" "*.Mask")
			(remove_unused_layers no)
			(net "TDR_DIFF_100_TOP_DIP")
			(clearance 0.10795)
			(thermal_gap 0.10795)
			(padstack
				(mode front_inner_back)
				(layer "Inner"
					(shape circle)
					(size 0.8001 0.8001)
					(clearance 0.1524)
				)
				(layer "B.Cu"
					(shape circle)
					(size 1.0033 1.0033)
					(clearance 0.10795)
				)
			)
		)
	)
	(footprint ""
		(layer "F.Cu")
		(at 144.149318 -280.994612 -90)
		(property "Reference" "C3194"
			(at 0 0 270)
			(layer "F.SilkS")
			(hide yes)
			(effects
				(font
					(size 1.27 1.27)
				)
			)
		)
		(property "Value" ""
			(at 0 0 270)
			(layer "F.Fab")
			(effects
				(font
					(size 1.27 1.27)
				)
			)
		)
		(duplicate_pad_numbers_are_jumpers no)
		(fp_line
			(start -0.299974 0.150114)
			(end -0.299974 -0.150114)
			(stroke
				(width 0.1)
				(type default)
			)
			(layer "F.Fab")
		)
		(fp_line
			(start 0.299974 0.150114)
			(end -0.299974 0.150114)
			(stroke
				(width 0.1)
				(type default)
			)
			(layer "F.Fab")
		)
		(fp_line
			(start -0.299974 -0.150114)
			(end 0.299974 -0.150114)
			(stroke
				(width 0.1)
				(type default)
			)
			(layer "F.Fab")
		)
		(fp_line
			(start 0.299974 -0.150114)
			(end 0.299974 0.150114)
			(stroke
				(width 0.1)
				(type default)
			)
			(layer "F.Fab")
		)
		(pad "1" smd rect
			(at -0.2667 0 270)
			(size 0.3048 0.381)
			(layers "F.Cu" "F.Mask" "F.Paste")
			(net "P1V8_PLL0_PEX1")
		)
		(pad "2" smd rect
			(at 0.2667 0 270)
			(size 0.3048 0.381)
			(layers "F.Cu" "F.Mask" "F.Paste")
			(net "GND")
		)
	)
	(footprint ""
		(layer "F.Cu")
		(at 430.961546 -135.28675 180)
		(property "Reference" "C651"
			(at 0 0 180)
			(layer "F.SilkS")
			(hide yes)
			(effects
				(font
					(size 1.27 1.27)
				)
			)
		)
		(property "Value" ""
			(at 0 0 180)
			(layer "F.Fab")
			(effects
				(font
					(size 1.27 1.27)
				)
			)
		)
		(duplicate_pad_numbers_are_jumpers no)
		(fp_line
			(start 0.299974 0.150114)
			(end -0.299974 0.150114)
			(stroke
				(width 0.1)
				(type default)
			)
			(layer "F.Fab")
		)
		(fp_line
			(start 0.299974 -0.150114)
			(end 0.299974 0.150114)
			(stroke
				(width 0.1)
				(type default)
			)
			(layer "F.Fab")
		)
		(fp_line
			(start -0.299974 0.150114)
			(end -0.299974 -0.150114)
			(stroke
				(width 0.1)
				(type default)
			)
			(layer "F.Fab")
		)
		(fp_line
			(start -0.299974 -0.150114)
			(end 0.299974 -0.150114)
			(stroke
				(width 0.1)
				(type default)
			)
			(layer "F.Fab")
		)
		(pad "1" smd rect
			(at -0.2667 0 180)
			(size 0.3048 0.381)
			(layers "F.Cu" "F.Mask" "F.Paste")
			(net "P5E_PEX3_STN0_TX_DN<7>")
		)
		(pad "2" smd rect
			(at 0.2667 0 180)
			(size 0.3048 0.381)
			(layers "F.Cu" "F.Mask" "F.Paste")
			(net "P5E_PEX3_STN0_TX_C_DN<7>")
		)
	)
)
